(kicad_pcb
	(version 20260206)
	(generator "pcbnew")
	(generator_version "10.0")
	(general
		(thickness 1.6)
		(legacy_teardrops no)
	)
	(paper "A4")
	(title_block
		(title "01162023_DA0F0TEBIF0_F0T_Expander_BD_F_brd_V02_OCP.brd")
		(comment 1 "Grand Teton / footprints 6748-6753 of 9728")
	)
	(layers
		(0 "F.Cu" signal "TOP")
		(4 "In1.Cu" signal "GND")
		(6 "In2.Cu" signal "VCC")
		(8 "In3.Cu" signal "VCC1")
		(10 "In4.Cu" signal "GND1")
		(12 "In5.Cu" signal "IN1")
		(14 "In6.Cu" signal "GND2")
		(16 "In7.Cu" signal "IN2")
		(18 "In8.Cu" signal "GND3")
		(20 "In9.Cu" signal "IN3")
		(22 "In10.Cu" signal "GND4")
		(24 "In11.Cu" signal "IN4")
		(26 "In12.Cu" signal "GND5")
		(28 "In13.Cu" signal "IN5")
		(30 "In14.Cu" signal "GND6")
		(32 "In15.Cu" signal "IN6")
		(34 "In16.Cu" signal "GND7")
		(2 "B.Cu" signal "BOTTOM")
		(9 "F.Adhes" user "F.Adhesive")
		(11 "B.Adhes" user "B.Adhesive")
		(13 "F.Paste" user "Package Geometry/Pastemask Top")
		(15 "B.Paste" user "Package Geometry/Pastemask Bottom")
		(5 "F.SilkS" user "Ref Des/Silkscreen Top")
		(7 "B.SilkS" user "Ref Des/Silkscreen Bottom")
		(1 "F.Mask" user "Board Geometry/Soldermask Top")
		(3 "B.Mask" user "Board Geometry/Soldermask Bottom")
		(17 "Dwgs.User" user "User.Drawings")
		(19 "Cmts.User" user "User.Comments")
		(21 "Eco1.User" user "User.Eco1")
		(23 "Eco2.User" user "User.Eco2")
		(25 "Edge.Cuts" user "Board Geometry/Outline")
		(27 "Margin" user)
		(31 "F.CrtYd" user "Package Geometry/Place Bound Top")
		(29 "B.CrtYd" user "Package Geometry/Place Bound Bottom")
		(35 "F.Fab" user "Ref Des/Assembly Top")
		(33 "B.Fab" user "Ref Des/Assembly Bottom")
	)
	(footprint ""
		(layer "F.Cu")
		(at 313.075066 -63.086234)
		(property "Reference" "R6009"
			(at 0 0 0)
			(layer "F.SilkS")
			(hide yes)
			(effects
				(font
					(size 1.27 1.27)
				)
			)
		)
		(property "Value" ""
			(at 0 0 0)
			(layer "F.Fab")
			(effects
				(font
					(size 1.27 1.27)
				)
			)
		)
		(duplicate_pad_numbers_are_jumpers no)
		(fp_line
			(start -0.7874 -0.4064)
			(end 0.7874 -0.4064)
			(stroke
				(width 0.1524)
				(type default)
			)
			(layer "F.SilkS")
		)
		(fp_line
			(start -0.7874 0.4064)
			(end -0.7874 -0.4064)
			(stroke
				(width 0.1524)
				(type default)
			)
			(layer "F.SilkS")
		)
		(fp_line
			(start 0.7874 -0.4064)
			(end 0.7874 0.4064)
			(stroke
				(width 0.1524)
				(type default)
			)
			(layer "F.SilkS")
		)
		(fp_line
			(start 0.7874 0.4064)
			(end -0.7874 0.4064)
			(stroke
				(width 0.1524)
				(type default)
			)
			(layer "F.SilkS")
		)
		(fp_line
			(start -0.67945 -0.305054)
			(end -0.12065 -0.305054)
			(stroke
				(width 0.1)
				(type default)
			)
			(layer "F.Fab")
		)
		(fp_line
			(start -0.67945 0.3048)
			(end -0.67945 -0.305054)
			(stroke
				(width 0.1)
				(type default)
			)
			(layer "F.Fab")
		)
		(fp_line
			(start -0.12065 -0.305054)
			(end -0.12065 -0.2794)
			(stroke
				(width 0.1)
				(type default)
			)
			(layer "F.Fab")
		)
		(fp_line
			(start -0.12065 -0.2794)
			(end 0.12065 -0.2794)
			(stroke
				(width 0.1)
				(type default)
			)
			(layer "F.Fab")
		)
		(fp_line
			(start -0.12065 0.2794)
			(end -0.12065 0.3048)
			(stroke
				(width 0.1)
				(type default)
			)
			(layer "F.Fab")
		)
		(fp_line
			(start -0.12065 0.3048)
			(end -0.67945 0.3048)
			(stroke
				(width 0.1)
				(type default)
			)
			(layer "F.Fab")
		)
		(fp_line
			(start 0.120396 0.2794)
			(end -0.12065 0.2794)
			(stroke
				(width 0.1)
				(type default)
			)
			(layer "F.Fab")
		)
		(fp_line
			(start 0.120396 0.3048)
			(end 0.120396 0.2794)
			(stroke
				(width 0.1)
				(type default)
			)
			(layer "F.Fab")
		)
		(fp_line
			(start 0.12065 -0.3048)
			(end 0.67945 -0.3048)
			(stroke
				(width 0.1)
				(type default)
			)
			(layer "F.Fab")
		)
		(fp_line
			(start 0.12065 -0.2794)
			(end 0.12065 -0.3048)
			(stroke
				(width 0.1)
				(type default)
			)
			(layer "F.Fab")
		)
		(fp_line
			(start 0.67945 -0.3048)
			(end 0.67945 0.3048)
			(stroke
				(width 0.1)
				(type default)
			)
			(layer "F.Fab")
		)
		(fp_line
			(start 0.67945 0.3048)
			(end 0.120396 0.3048)
			(stroke
				(width 0.1)
				(type default)
			)
			(layer "F.Fab")
		)
		(pad "1" smd circle
			(at -0.40005 0)
			(size 0 0)
			(layers "F.Cu" "F.Mask" "F.Paste")
			(net "P12V_SSD11_R")
		)
		(pad "2" smd circle
			(at 0.40005 0)
			(size 0 0)
			(layers "F.Cu" "F.Mask" "F.Paste")
			(net "P12V_SSD11_PG_G1")
		)
	)
	(footprint ""
		(layer "F.Cu")
		(at 206.793592 -350.312482 -90)
		(property "Reference" "C3869"
			(at 0 0 270)
			(layer "F.SilkS")
			(hide yes)
			(effects
				(font
					(size 1.27 1.27)
				)
			)
		)
		(property "Value" ""
			(at 0 0 270)
			(layer "F.Fab")
			(effects
				(font
					(size 1.27 1.27)
				)
			)
		)
		(duplicate_pad_numbers_are_jumpers no)
		(fp_line
			(start -0.7874 0.4064)
			(end -0.7874 -0.4064)
			(stroke
				(width 0.1524)
				(type default)
			)
			(layer "F.SilkS")
		)
		(fp_line
			(start 0.7874 0.4064)
			(end -0.7874 0.4064)
			(stroke
				(width 0.1524)
				(type default)
			)
			(layer "F.SilkS")
		)
		(fp_line
			(start -0.7874 -0.4064)
			(end 0.7874 -0.4064)
			(stroke
				(width 0.1524)
				(type default)
			)
			(layer "F.SilkS")
		)
		(fp_line
			(start 0.7874 -0.4064)
			(end 0.7874 0.4064)
			(stroke
				(width 0.1524)
				(type default)
			)
			(layer "F.SilkS")
		)
		(fp_line
			(start -0.67945 0.3048)
			(end -0.67945 -0.305054)
			(stroke
				(width 0.1)
				(type default)
			)
			(layer "F.Fab")
		)
		(fp_line
			(start -0.12065 0.3048)
			(end -0.67945 0.3048)
			(stroke
				(width 0.1)
				(type default)
			)
			(layer "F.Fab")
		)
		(fp_line
			(start 0.120396 0.3048)
			(end 0.120396 0.2794)
			(stroke
				(width 0.1)
				(type default)
			)
			(layer "F.Fab")
		)
		(fp_line
			(start 0.67945 0.3048)
			(end 0.120396 0.3048)
			(stroke
				(width 0.1)
				(type default)
			)
			(layer "F.Fab")
		)
		(fp_line
			(start -0.12065 0.2794)
			(end -0.12065 0.3048)
			(stroke
				(width 0.1)
				(type default)
			)
			(layer "F.Fab")
		)
		(fp_line
			(start 0.120396 0.2794)
			(end -0.12065 0.2794)
			(stroke
				(width 0.1)
				(type default)
			)
			(layer "F.Fab")
		)
		(fp_line
			(start -0.12065 -0.2794)
			(end 0.12065 -0.2794)
			(stroke
				(width 0.1)
				(type default)
			)
			(layer "F.Fab")
		)
		(fp_line
			(start 0.12065 -0.2794)
			(end 0.12065 -0.3048)
			(stroke
				(width 0.1)
				(type default)
			)
			(layer "F.Fab")
		)
		(fp_line
			(start 0.12065 -0.3048)
			(end 0.67945 -0.3048)
			(stroke
				(width 0.1)
				(type default)
			)
			(layer "F.Fab")
		)
		(fp_line
			(start 0.67945 -0.3048)
			(end 0.67945 0.3048)
			(stroke
				(width 0.1)
				(type default)
			)
			(layer "F.Fab")
		)
		(fp_line
			(start -0.67945 -0.305054)
			(end -0.12065 -0.305054)
			(stroke
				(width 0.1)
				(type default)
			)
			(layer "F.Fab")
		)
		(fp_line
			(start -0.12065 -0.305054)
			(end -0.12065 -0.2794)
			(stroke
				(width 0.1)
				(type default)
			)
			(layer "F.Fab")
		)
		(pad "1" smd circle
			(at -0.40005 0 270)
			(size 0 0)
			(layers "F.Cu" "F.Mask" "F.Paste")
			(net "P3V3_AUX")
		)
		(pad "2" smd circle
			(at 0.40005 0 270)
			(size 0 0)
			(layers "F.Cu" "F.Mask" "F.Paste")
			(net "GND")
		)
	)
	(footprint ""
		(layer "F.Cu")
		(at 326.667368 -112.903508 90)
		(property "Reference" "PC805"
			(at 0 0 90)
			(layer "F.SilkS")
			(hide yes)
			(effects
				(font
					(size 1.27 1.27)
				)
			)
		)
		(property "Value" ""
			(at 0 0 90)
			(layer "F.Fab")
			(effects
				(font
					(size 1.27 1.27)
				)
			)
		)
		(duplicate_pad_numbers_are_jumpers no)
		(fp_line
			(start 1.524 -0.762)
			(end 1.524 0.762)
			(stroke
				(width 0.1524)
				(type default)
			)
			(layer "F.SilkS")
		)
		(fp_line
			(start -1.524 -0.762)
			(end 1.524 -0.762)
			(stroke
				(width 0.1524)
				(type default)
			)
			(layer "F.SilkS")
		)
		(fp_line
			(start 1.524 0.762)
			(end -1.524 0.762)
			(stroke
				(width 0.1524)
				(type default)
			)
			(layer "F.SilkS")
		)
		(fp_line
			(start -1.524 0.762)
			(end -1.524 -0.762)
			(stroke
				(width 0.1524)
				(type default)
			)
			(layer "F.SilkS")
		)
		(fp_line
			(start 1.1049 -0.724916)
			(end -1.1049 -0.724916)
			(stroke
				(width 0.1)
				(type default)
			)
			(layer "F.Fab")
		)
		(fp_line
			(start -1.1049 -0.724916)
			(end -1.1049 0.724916)
			(stroke
				(width 0.1)
				(type default)
			)
			(layer "F.Fab")
		)
		(fp_line
			(start 1.1049 0.724916)
			(end 1.1049 -0.724916)
			(stroke
				(width 0.1)
				(type default)
			)
			(layer "F.Fab")
		)
		(fp_line
			(start -1.1049 0.724916)
			(end 1.1049 0.724916)
			(stroke
				(width 0.1)
				(type default)
			)
			(layer "F.Fab")
		)
		(pad "1" smd rect
			(at -0.889 0 270)
			(size 1.016 1.27)
			(layers "F.Cu" "F.Mask" "F.Paste")
			(net "P12V_NIC5_R")
		)
		(pad "2" smd rect
			(at 0.889 0 270)
			(size 1.016 1.27)
			(layers "F.Cu" "F.Mask" "F.Paste")
			(net "GND")
		)
	)
	(footprint ""
		(layer "F.Cu")
		(at 213.806024 18.035524)
		(property "Reference" "DE01F_2"
			(at -3.6068 -2.962148 0)
			(unlocked yes)
			(layer "F.SilkS")
			(effects
				(font
					(size 0.7874 0.5842)
					(thickness 0.1524)
				)
				(justify left)
			)
		)
		(property "Value" ""
			(at 0 0 0)
			(layer "F.Fab")
			(effects
				(font
					(size 1.27 1.27)
				)
			)
		)
		(duplicate_pad_numbers_are_jumpers no)
		(pad "" np_thru_hole circle
			(at -2.8829 -1.27 270)
			(size 1.0414 1.0414)
			(drill 1.0414)
			(layers "*.Cu" "*.Mask")
			(clearance 0.381)
			(thermal_gap 0.381)
		)
		(pad "" np_thru_hole circle
			(at -2.8829 1.27 270)
			(size 1.0414 1.0414)
			(drill 1.0414)
			(layers "*.Cu" "*.Mask")
			(clearance 0.381)
			(thermal_gap 0.381)
		)
		(pad "" np_thru_hole circle
			(at 3.4671 -1.27 270)
			(size 1.0414 1.0414)
			(drill 1.0414)
			(layers "*.Cu" "*.Mask")
			(clearance 0.381)
			(thermal_gap 0.381)
		)
		(pad "" np_thru_hole circle
			(at 3.4671 1.27 270)
			(size 1.0414 1.0414)
			(drill 1.0414)
			(layers "*.Cu" "*.Mask")
			(clearance 0.381)
			(thermal_gap 0.381)
		)
		(pad "1" smd rect
			(at 0.8255 -0.249936 270)
			(size 0.3048 0.508)
			(layers "F.Cu" "F.Mask" "F.Paste")
			(net "85_5INCH_TOP_DN")
		)
		(pad "2" smd rect
			(at 0.8255 0.249936 270)
			(size 0.3048 0.508)
			(layers "F.Cu" "F.Mask" "F.Paste")
			(net "85_5INCH_TOP_DP")
		)
		(pad "3" smd circle
			(at 0 0)
			(size 0 0)
			(layers "F.Cu" "F.Mask" "F.Paste")
			(net "COUPON_GND2")
		)
		(zone
			(layer "F.Cu")
			(hatch none 0.5)
			(connect_pads
				(clearance 0)
			)
			(min_thickness 0.25)
			(keepout
				(tracks not_allowed)
				(vias allowed)
				(pads allowed)
				(copperpour not_allowed)
				(footprints allowed)
			)
			(placement
				(enabled no)
				(sheetname "")
			)
			(fill
				(thermal_gap 0.5)
				(thermal_bridge_width 0.5)
				(island_removal_mode 0)
			)
			(polygon
				(pts
					(xy 214.923624 17.486884) (xy 214.923624 17.582388) (xy 214.326724 17.582388) (xy 214.326724 17.988788)
					(xy 214.923624 17.988788) (xy 214.923624 18.08226) (xy 214.326724 18.08226) (xy 214.326724 18.48866)
					(xy 214.923624 18.48866) (xy 214.923624 18.584164) (xy 214.225124 18.584164) (xy 214.225124 17.486884)
				)
			)
		)
		(zone
			(layers "F.Cu" "B.Cu" "In1.Cu" "In2.Cu" "In3.Cu" "In4.Cu" "In5.Cu" "In6.Cu"
				"In7.Cu" "In8.Cu" "In9.Cu" "In10.Cu" "In11.Cu" "In12.Cu" "In13.Cu" "In14.Cu"
				"In15.Cu" "In16.Cu"
			)
			(hatch none 0.5)
			(connect_pads
				(clearance 0)
			)
			(min_thickness 0.25)
			(keepout
				(tracks not_allowed)
				(vias allowed)
				(pads allowed)
				(copperpour not_allowed)
				(footprints allowed)
			)
			(placement
				(enabled no)
				(sheetname "")
			)
			(fill
				(thermal_gap 0.5)
				(thermal_bridge_width 0.5)
				(island_removal_mode 0)
			)
			(polygon
				(pts
					(arc
						(start 211.850224 16.765524)
						(mid 209.996024 16.765524)
						(end 211.850224 16.765524)
					)
				)
			)
		)
		(zone
			(layers "F.Cu" "B.Cu" "In1.Cu" "In2.Cu" "In3.Cu" "In4.Cu" "In5.Cu" "In6.Cu"
				"In7.Cu" "In8.Cu" "In9.Cu" "In10.Cu" "In11.Cu" "In12.Cu" "In13.Cu" "In14.Cu"
				"In15.Cu" "In16.Cu"
			)
			(hatch none 0.5)
			(connect_pads
				(clearance 0)
			)
			(min_thickness 0.25)
			(keepout
				(tracks not_allowed)
				(vias allowed)
				(pads allowed)
				(copperpour not_allowed)
				(footprints allowed)
			)
			(placement
				(enabled no)
				(sheetname "")
			)
			(fill
				(thermal_gap 0.5)
				(thermal_bridge_width 0.5)
				(island_removal_mode 0)
			)
			(polygon
				(pts
					(arc
						(start 211.850224 19.305524)
						(mid 209.996024 19.305524)
						(end 211.850224 19.305524)
					)
				)
			)
		)
		(zone
			(layers "F.Cu" "B.Cu" "In1.Cu" "In2.Cu" "In3.Cu" "In4.Cu" "In5.Cu" "In6.Cu"
				"In7.Cu" "In8.Cu" "In9.Cu" "In10.Cu" "In11.Cu" "In12.Cu" "In13.Cu" "In14.Cu"
				"In15.Cu" "In16.Cu"
			)
			(hatch none 0.5)
			(connect_pads
				(clearance 0)
			)
			(min_thickness 0.25)
			(keepout
				(tracks not_allowed)
				(vias allowed)
				(pads allowed)
				(copperpour not_allowed)
				(footprints allowed)
			)
			(placement
				(enabled no)
				(sheetname "")
			)
			(fill
				(thermal_gap 0.5)
				(thermal_bridge_width 0.5)
				(island_removal_mode 0)
			)
			(polygon
				(pts
					(arc
						(start 218.200224 16.765524)
						(mid 216.346024 16.765524)
						(end 218.200224 16.765524)
					)
				)
			)
		)
		(zone
			(layers "F.Cu" "B.Cu" "In1.Cu" "In2.Cu" "In3.Cu" "In4.Cu" "In5.Cu" "In6.Cu"
				"In7.Cu" "In8.Cu" "In9.Cu" "In10.Cu" "In11.Cu" "In12.Cu" "In13.Cu" "In14.Cu"
				"In15.Cu" "In16.Cu"
			)
			(hatch none 0.5)
			(connect_pads
				(clearance 0)
			)
			(min_thickness 0.25)
			(keepout
				(tracks not_allowed)
				(vias allowed)
				(pads allowed)
				(copperpour not_allowed)
				(footprints allowed)
			)
			(placement
				(enabled no)
				(sheetname "")
			)
			(fill
				(thermal_gap 0.5)
				(thermal_bridge_width 0.5)
				(island_removal_mode 0)
			)
			(polygon
				(pts
					(arc
						(start 218.200224 19.305524)
						(mid 216.346024 19.305524)
						(end 218.200224 19.305524)
					)
				)
			)
		)
	)
	(footprint ""
		(layer "F.Cu")
		(at 419.189408 -230.956866 180)
		(property "Reference" "R6617"
			(at 0 0 180)
			(layer "F.SilkS")
			(hide yes)
			(effects
				(font
					(size 1.27 1.27)
				)
			)
		)
		(property "Value" ""
			(at 0 0 180)
			(layer "F.Fab")
			(effects
				(font
					(size 1.27 1.27)
				)
			)
		)
		(duplicate_pad_numbers_are_jumpers no)
		(fp_line
			(start 0.7874 0.4064)
			(end -0.7874 0.4064)
			(stroke
				(width 0.1524)
				(type default)
			)
			(layer "F.SilkS")
		)
		(fp_line
			(start 0.7874 -0.4064)
			(end 0.7874 0.4064)
			(stroke
				(width 0.1524)
				(type default)
			)
			(layer "F.SilkS")
		)
		(fp_line
			(start -0.7874 0.4064)
			(end -0.7874 -0.4064)
			(stroke
				(width 0.1524)
				(type default)
			)
			(layer "F.SilkS")
		)
		(fp_line
			(start -0.7874 -0.4064)
			(end 0.7874 -0.4064)
			(stroke
				(width 0.1524)
				(type default)
			)
			(layer "F.SilkS")
		)
		(fp_line
			(start 0.67945 0.3048)
			(end 0.120396 0.3048)
			(stroke
				(width 0.1)
				(type default)
			)
			(layer "F.Fab")
		)
		(fp_line
			(start 0.67945 -0.3048)
			(end 0.67945 0.3048)
			(stroke
				(width 0.1)
				(type default)
			)
			(layer "F.Fab")
		)
		(fp_line
			(start 0.12065 -0.2794)
			(end 0.12065 -0.3048)
			(stroke
				(width 0.1)
				(type default)
			)
			(layer "F.Fab")
		)
		(fp_line
			(start 0.12065 -0.3048)
			(end 0.67945 -0.3048)
			(stroke
				(width 0.1)
				(type default)
			)
			(layer "F.Fab")
		)
		(fp_line
			(start 0.120396 0.3048)
			(end 0.120396 0.2794)
			(stroke
				(width 0.1)
				(type default)
			)
			(layer "F.Fab")
		)
		(fp_line
			(start 0.120396 0.2794)
			(end -0.12065 0.2794)
			(stroke
				(width 0.1)
				(type default)
			)
			(layer "F.Fab")
		)
		(fp_line
			(start -0.12065 0.3048)
			(end -0.67945 0.3048)
			(stroke
				(width 0.1)
				(type default)
			)
			(layer "F.Fab")
		)
		(fp_line
			(start -0.12065 0.2794)
			(end -0.12065 0.3048)
			(stroke
				(width 0.1)
				(type default)
			)
			(layer "F.Fab")
		)
		(fp_line
			(start -0.12065 -0.2794)
			(end 0.12065 -0.2794)
			(stroke
				(width 0.1)
				(type default)
			)
			(layer "F.Fab")
		)
		(fp_line
			(start -0.12065 -0.305054)
			(end -0.12065 -0.2794)
			(stroke
				(width 0.1)
				(type default)
			)
			(layer "F.Fab")
		)
		(fp_line
			(start -0.67945 0.3048)
			(end -0.67945 -0.305054)
			(stroke
				(width 0.1)
				(type default)
			)
			(layer "F.Fab")
		)
		(fp_line
			(start -0.67945 -0.305054)
			(end -0.12065 -0.305054)
			(stroke
				(width 0.1)
				(type default)
			)
			(layer "F.Fab")
		)
		(pad "1" smd circle
			(at -0.40005 0 180)
			(size 0 0)
			(layers "F.Cu" "F.Mask" "F.Paste")
			(net "UART_PEX3_SDB_R_RX")
		)
		(pad "2" smd circle
			(at 0.40005 0 180)
			(size 0 0)
			(layers "F.Cu" "F.Mask" "F.Paste")
			(net "UART_PEX3_SDB_R1_RX")
		)
	)
	(footprint ""
		(layer "F.Cu")
		(at 199.001888 -32.849312 90)
		(property "Reference" "R5674"
			(at 0 0 90)
			(layer "F.SilkS")
			(hide yes)
			(effects
				(font
					(size 1.27 1.27)
				)
			)
		)
		(property "Value" ""
			(at 0 0 90)
			(layer "F.Fab")
			(effects
				(font
					(size 1.27 1.27)
				)
			)
		)
		(duplicate_pad_numbers_are_jumpers no)
		(fp_line
			(start 0.7874 -0.4064)
			(end 0.7874 0.4064)
			(stroke
				(width 0.1524)
				(type default)
			)
			(layer "F.SilkS")
		)
		(fp_line
			(start -0.7874 -0.4064)
			(end 0.7874 -0.4064)
			(stroke
				(width 0.1524)
				(type default)
			)
			(layer "F.SilkS")
		)
		(fp_line
			(start 0.7874 0.4064)
			(end -0.7874 0.4064)
			(stroke
				(width 0.1524)
				(type default)
			)
			(layer "F.SilkS")
		)
		(fp_line
			(start -0.7874 0.4064)
			(end -0.7874 -0.4064)
			(stroke
				(width 0.1524)
				(type default)
			)
			(layer "F.SilkS")
		)
		(fp_line
			(start -0.12065 -0.305054)
			(end -0.12065 -0.2794)
			(stroke
				(width 0.1)
				(type default)
			)
			(layer "F.Fab")
		)
		(fp_line
			(start -0.67945 -0.305054)
			(end -0.12065 -0.305054)
			(stroke
				(width 0.1)
				(type default)
			)
			(layer "F.Fab")
		)
		(fp_line
			(start 0.67945 -0.3048)
			(end 0.67945 0.3048)
			(stroke
				(width 0.1)
				(type default)
			)
			(layer "F.Fab")
		)
		(fp_line
			(start 0.12065 -0.3048)
			(end 0.67945 -0.3048)
			(stroke
				(width 0.1)
				(type default)
			)
			(layer "F.Fab")
		)
		(fp_line
			(start 0.12065 -0.2794)
			(end 0.12065 -0.3048)
			(stroke
				(width 0.1)
				(type default)
			)
			(layer "F.Fab")
		)
		(fp_line
			(start -0.12065 -0.2794)
			(end 0.12065 -0.2794)
			(stroke
				(width 0.1)
				(type default)
			)
			(layer "F.Fab")
		)
		(fp_line
			(start 0.120396 0.2794)
			(end -0.12065 0.2794)
			(stroke
				(width 0.1)
				(type default)
			)
			(layer "F.Fab")
		)
		(fp_line
			(start -0.12065 0.2794)
			(end -0.12065 0.3048)
			(stroke
				(width 0.1)
				(type default)
			)
			(layer "F.Fab")
		)
		(fp_line
			(start 0.67945 0.3048)
			(end 0.120396 0.3048)
			(stroke
				(width 0.1)
				(type default)
			)
			(layer "F.Fab")
		)
		(fp_line
			(start 0.120396 0.3048)
			(end 0.120396 0.2794)
			(stroke
				(width 0.1)
				(type default)
			)
			(layer "F.Fab")
		)
		(fp_line
			(start -0.12065 0.3048)
			(end -0.67945 0.3048)
			(stroke
				(width 0.1)
				(type default)
			)
			(layer "F.Fab")
		)
		(fp_line
			(start -0.67945 0.3048)
			(end -0.67945 -0.305054)
			(stroke
				(width 0.1)
				(type default)
			)
			(layer "F.Fab")
		)
		(pad "1" smd circle
			(at -0.40005 0 90)
			(size 0 0)
			(layers "F.Cu" "F.Mask" "F.Paste")
			(net "RST_SMB_SSD7_ISO_R_N")
		)
		(pad "2" smd circle
			(at 0.40005 0 90)
			(size 0 0)
			(layers "F.Cu" "F.Mask" "F.Paste")
			(net "RST_SMB_SSD7_ISO_N")
		)
	)
)
